(kicad_pcb
	(version 20260206)
	(generator "pcbnew")
	(generator_version "10.0")
	(general
		(thickness 1.6)
		(legacy_teardrops no)
	)
	(paper "A4")
	(title_block
		(title "Bryce Canyon_IOM_IOC_16318-2_OCP.brd")
		(comment 1 "Bryce Canyon / footprints 810-817 of 1605")
	)
	(layers
		(0 "F.Cu" signal "TOP")
		(4 "In1.Cu" signal "L2GND")
		(6 "In2.Cu" signal "L3")
		(8 "In3.Cu" signal "L4VCC")
		(10 "In4.Cu" signal "L5VCC")
		(12 "In5.Cu" signal "L6")
		(14 "In6.Cu" signal "L7GND")
		(2 "B.Cu" signal "BOTTOM")
		(9 "F.Adhes" user "F.Adhesive")
		(11 "B.Adhes" user "B.Adhesive")
		(13 "F.Paste" user "Package Geometry/Pastemask Top")
		(15 "B.Paste" user "Package Geometry/Pastemask Bottom")
		(5 "F.SilkS" user "Ref Des/Silkscreen Top")
		(7 "B.SilkS" user "Ref Des/Silkscreen Bottom")
		(1 "F.Mask" user "Board Geometry/Soldermask Top")
		(3 "B.Mask" user "Board Geometry/Soldermask Bottom")
		(17 "Dwgs.User" user "User.Drawings")
		(19 "Cmts.User" user "User.Comments")
		(21 "Eco1.User" user "User.Eco1")
		(23 "Eco2.User" user "User.Eco2")
		(25 "Edge.Cuts" user "Board Geometry/Outline")
		(27 "Margin" user)
		(31 "F.CrtYd" user "Package Geometry/Place Bound Top")
		(29 "B.CrtYd" user "Package Geometry/Place Bound Bottom")
		(35 "F.Fab" user "Ref Des/Assembly Top")
		(33 "B.Fab" user "Ref Des/Assembly Bottom")
	)
	(footprint ""
		(layer "F.Cu")
		(at 26.90368 -124.820172)
		(property "Reference" "R789"
			(at 0 0 0)
			(layer "F.SilkS")
			(hide yes)
			(effects
				(font
					(size 1.27 1.27)
				)
			)
		)
		(property "Value" "0R2J-2-GP"
			(at 0.064008 -3.993896 0)
			(unlocked yes)
			(layer "F.Fab")
			(hide yes)
			(effects
				(font
					(size 1.016 1.016)
					(thickness 0.1524)
				)
			)
		)
		(property "Device Type" "R402H16"
			(at 0.064008 -5.517896 0)
			(unlocked yes)
			(layer "F.Fab")
			(hide yes)
			(effects
				(font
					(size 1.016 1.016)
					(thickness 0.1524)
				)
			)
		)
		(duplicate_pad_numbers_are_jumpers no)
		(fp_line
			(start -0.508 -0.9398)
			(end -0.508 0.9398)
			(stroke
				(width 0.1524)
				(type default)
			)
			(layer "F.SilkS")
		)
		(fp_line
			(start 0.508 -0.9398)
			(end -0.508 -0.9398)
			(stroke
				(width 0.1524)
				(type default)
			)
			(layer "F.SilkS")
		)
		(fp_rect
			(start -0.508 0.9398)
			(end 0.508 -0.9398)
			(stroke
				(width 0)
				(type default)
			)
			(fill no)
			(layer "F.CrtYd")
		)
		(fp_rect
			(start -0.508 0.9398)
			(end 0.508 -0.9398)
			(stroke
				(width 0)
				(type default)
			)
			(fill no)
			(layer "F.Fab")
		)
		(pad "1" smd custom
			(at 0 -0.4445)
			(size 0.1397 0.1397)
			(layers "F.Cu" "F.Mask" "F.Paste")
			(net "FLA0_WP_N")
			(options
				(clearance outline)
				(anchor circle)
			)
			(primitives
				(gr_poly
					(pts
						(arc
							(start -0.1778 -0.2794)
							(mid -0.249642 -0.249642)
							(end -0.2794 -0.1778)
						)
						(arc
							(start -0.2794 0.1778)
							(mid -0.249642 0.249642)
							(end -0.1778 0.2794)
						)
						(arc
							(start 0.1778 0.2794)
							(mid 0.249642 0.249642)
							(end 0.2794 0.1778)
						)
						(arc
							(start 0.2794 -0.1778)
							(mid 0.249642 -0.249642)
							(end 0.1778 -0.2794)
						)
					)
					(width 0)
					(fill yes)
				)
			)
		)
		(pad "2" smd custom
			(at 0 0.4445)
			(size 0.1397 0.1397)
			(layers "F.Cu" "F.Mask" "F.Paste")
			(net "WP_DISABLE")
			(options
				(clearance outline)
				(anchor circle)
			)
			(primitives
				(gr_poly
					(pts
						(arc
							(start -0.1778 -0.2794)
							(mid -0.249642 -0.249642)
							(end -0.2794 -0.1778)
						)
						(arc
							(start -0.2794 0.1778)
							(mid -0.249642 0.249642)
							(end -0.1778 0.2794)
						)
						(arc
							(start 0.1778 0.2794)
							(mid 0.249642 0.249642)
							(end 0.2794 0.1778)
						)
						(arc
							(start 0.2794 -0.1778)
							(mid 0.249642 -0.249642)
							(end 0.1778 -0.2794)
						)
					)
					(width 0)
					(fill yes)
				)
			)
		)
	)
	(footprint ""
		(layer "F.Cu")
		(at 52.963064 -166.421054)
		(property "Reference" "R776"
			(at 0 0 0)
			(layer "F.SilkS")
			(hide yes)
			(effects
				(font
					(size 1.27 1.27)
				)
			)
		)
		(property "Value" "1KR2F-3-GP"
			(at 0.064008 -3.993896 0)
			(unlocked yes)
			(layer "F.Fab")
			(hide yes)
			(effects
				(font
					(size 1.016 1.016)
					(thickness 0.1524)
				)
			)
		)
		(property "Device Type" "R402H16"
			(at 0.064008 -5.517896 0)
			(unlocked yes)
			(layer "F.Fab")
			(hide yes)
			(effects
				(font
					(size 1.016 1.016)
					(thickness 0.1524)
				)
			)
		)
		(duplicate_pad_numbers_are_jumpers no)
		(fp_line
			(start -0.508 -0.9398)
			(end -0.508 0.9398)
			(stroke
				(width 0.1524)
				(type default)
			)
			(layer "F.SilkS")
		)
		(fp_line
			(start 0.508 -0.9398)
			(end -0.508 -0.9398)
			(stroke
				(width 0.1524)
				(type default)
			)
			(layer "F.SilkS")
		)
		(fp_rect
			(start -0.508 0.9398)
			(end 0.508 -0.9398)
			(stroke
				(width 0)
				(type default)
			)
			(fill no)
			(layer "F.CrtYd")
		)
		(fp_rect
			(start -0.508 0.9398)
			(end 0.508 -0.9398)
			(stroke
				(width 0)
				(type default)
			)
			(fill no)
			(layer "F.Fab")
		)
		(pad "1" smd custom
			(at 0 -0.4445)
			(size 0.1397 0.1397)
			(layers "F.Cu" "F.Mask" "F.Paste")
			(net "P1V2_STBY")
			(options
				(clearance outline)
				(anchor circle)
			)
			(primitives
				(gr_poly
					(pts
						(arc
							(start -0.1778 -0.2794)
							(mid -0.249642 -0.249642)
							(end -0.2794 -0.1778)
						)
						(arc
							(start -0.2794 0.1778)
							(mid -0.249642 0.249642)
							(end -0.1778 0.2794)
						)
						(arc
							(start 0.1778 0.2794)
							(mid 0.249642 0.249642)
							(end 0.2794 0.1778)
						)
						(arc
							(start 0.2794 -0.1778)
							(mid 0.249642 -0.249642)
							(end 0.1778 -0.2794)
						)
					)
					(width 0)
					(fill yes)
				)
			)
		)
		(pad "2" smd custom
			(at 0 0.4445)
			(size 0.1397 0.1397)
			(layers "F.Cu" "F.Mask" "F.Paste")
			(net "ADC_P1V2_STBY")
			(options
				(clearance outline)
				(anchor circle)
			)
			(primitives
				(gr_poly
					(pts
						(arc
							(start -0.1778 -0.2794)
							(mid -0.249642 -0.249642)
							(end -0.2794 -0.1778)
						)
						(arc
							(start -0.2794 0.1778)
							(mid -0.249642 0.249642)
							(end -0.1778 0.2794)
						)
						(arc
							(start 0.1778 0.2794)
							(mid 0.249642 0.249642)
							(end 0.2794 0.1778)
						)
						(arc
							(start 0.2794 -0.1778)
							(mid 0.249642 -0.249642)
							(end 0.1778 -0.2794)
						)
					)
					(width 0)
					(fill yes)
				)
			)
		)
	)
	(footprint ""
		(layer "F.Cu")
		(at 197.210172 -85.6488 135)
		(property "Reference" "VIA20"
			(at 0 0 135)
			(layer "F.SilkS")
			(hide yes)
			(effects
				(font
					(size 1.27 1.27)
				)
			)
		)
		(property "Value" "85OHM-8L-1D6MM-L16L18-GP"
			(at 4.064105 0.609655 135)
			(unlocked yes)
			(layer "F.Fab")
			(hide yes)
			(effects
				(font
					(size 1.016 1.016)
					(thickness 0.1524)
				)
			)
		)
		(property "Device Type" "VIA-PCIE-4P-368076"
			(at 4.064105 -0.914474 135)
			(unlocked yes)
			(layer "F.Fab")
			(hide yes)
			(effects
				(font
					(size 1.016 1.016)
					(thickness 0.1524)
				)
			)
		)
		(duplicate_pad_numbers_are_jumpers no)
		(fp_poly
			(pts
				(xy -1.841491 -0.381057) (xy 1.841509 -0.381058) (xy 1.841508 0.380942) (xy -1.841491 0.380942)
			)
			(stroke
				(width 0)
				(type default)
			)
			(fill no)
			(layer "F.CrtYd")
		)
		(fp_poly
			(pts
				(xy -1.841491 -0.381057) (xy 1.841509 -0.381058) (xy 1.841508 0.380942) (xy -1.841491 0.380942)
			)
			(stroke
				(width 0)
				(type default)
			)
			(fill no)
			(layer "F.Fab")
		)
		(pad "1" thru_hole circle
			(at -1.460499 0 135)
			(size 0.508 0.508)
			(drill 0.254)
			(layers "*.Cu" "*.Mask")
			(remove_unused_layers no)
			(net "GND")
			(clearance 0.127)
			(thermal_gap 0.127)
		)
		(pad "2" thru_hole circle
			(at -0.4445 0 135)
			(size 0.508 0.508)
			(drill 0.254)
			(layers "*.Cu" "*.Mask")
			(remove_unused_layers no)
			(net "PCIE_COMP_TO_IOM_11_DP")
			(clearance 0.127)
			(thermal_gap 0.127)
		)
		(pad "3" thru_hole circle
			(at 0.4445 0 135)
			(size 0.508 0.508)
			(drill 0.254)
			(layers "*.Cu" "*.Mask")
			(remove_unused_layers no)
			(net "PCIE_COMP_TO_IOM_11_DN")
			(clearance 0.127)
			(thermal_gap 0.127)
		)
		(pad "4" thru_hole circle
			(at 1.460499 0 135)
			(size 0.508 0.508)
			(drill 0.254)
			(layers "*.Cu" "*.Mask")
			(remove_unused_layers no)
			(net "GND")
			(clearance 0.127)
			(thermal_gap 0.127)
		)
	)
	(footprint ""
		(layer "F.Cu")
		(at 177.6222 -77.9526)
		(property "Reference" "TP107"
			(at 0 0 0)
			(layer "F.SilkS")
			(hide yes)
			(effects
				(font
					(size 1.27 1.27)
				)
			)
		)
		(property "Value" "TPAD28-2-GP"
			(at -0.0127 -1.6637 0)
			(unlocked yes)
			(layer "F.Fab")
			(hide yes)
			(effects
				(font
					(size 1.016 1.016)
					(thickness 0.1524)
				)
			)
		)
		(property "Device Type" "TPAD28"
			(at -0.0127 -3.1877 0)
			(unlocked yes)
			(layer "F.Fab")
			(hide yes)
			(effects
				(font
					(size 1.016 1.016)
					(thickness 0.1524)
				)
			)
		)
		(duplicate_pad_numbers_are_jumpers no)
		(fp_poly
			(pts
				(arc
					(start 0.3556 0)
					(mid -0.3556 0)
					(end 0.3556 0)
				)
			)
			(stroke
				(width 0)
				(type default)
			)
			(fill no)
			(layer "F.CrtYd")
		)
		(fp_poly
			(pts
				(arc
					(start 0.6096 0)
					(mid -0.6096 0)
					(end 0.6096 0)
				)
			)
			(stroke
				(width 0)
				(type default)
			)
			(fill no)
			(layer "F.Fab")
		)
		(pad "1" smd circle
			(at 0 0)
			(size 0.7112 0.7112)
			(layers "F.Cu" "F.Mask" "F.Paste")
			(net "IOC_GPIO_22")
		)
	)
	(footprint ""
		(layer "F.Cu")
		(at 16.013684 -164.5539 90)
		(property "Reference" "R531"
			(at 0 0 90)
			(layer "F.SilkS")
			(hide yes)
			(effects
				(font
					(size 1.27 1.27)
				)
			)
		)
		(property "Value" "4K99R2F-L-GP"
			(at 0.064008 -3.993896 90)
			(unlocked yes)
			(layer "F.Fab")
			(hide yes)
			(effects
				(font
					(size 1.016 1.016)
					(thickness 0.1524)
				)
			)
		)
		(property "Device Type" "R402H16"
			(at 0.064008 -5.517896 90)
			(unlocked yes)
			(layer "F.Fab")
			(hide yes)
			(effects
				(font
					(size 1.016 1.016)
					(thickness 0.1524)
				)
			)
		)
		(duplicate_pad_numbers_are_jumpers no)
		(fp_line
			(start 0.508 -0.9398)
			(end -0.508 -0.9398)
			(stroke
				(width 0.1524)
				(type default)
			)
			(layer "F.SilkS")
		)
		(fp_line
			(start -0.508 -0.9398)
			(end -0.508 0.9398)
			(stroke
				(width 0.1524)
				(type default)
			)
			(layer "F.SilkS")
		)
		(fp_rect
			(start -0.508 0.9398)
			(end 0.508 -0.9398)
			(stroke
				(width 0)
				(type default)
			)
			(fill no)
			(layer "F.CrtYd")
		)
		(fp_rect
			(start -0.508 0.9398)
			(end 0.508 -0.9398)
			(stroke
				(width 0)
				(type default)
			)
			(fill no)
			(layer "F.Fab")
		)
		(pad "1" smd custom
			(at 0 -0.4445 90)
			(size 0.1397 0.1397)
			(layers "F.Cu" "F.Mask" "F.Paste")
			(net "TPS74801_P1V2_STBY_FB")
			(options
				(clearance outline)
				(anchor circle)
			)
			(primitives
				(gr_poly
					(pts
						(arc
							(start -0.1778 -0.2794)
							(mid -0.249642 -0.249642)
							(end -0.2794 -0.1778)
						)
						(arc
							(start -0.2794 0.1778)
							(mid -0.249642 0.249642)
							(end -0.1778 0.2794)
						)
						(arc
							(start 0.1778 0.2794)
							(mid 0.249642 0.249642)
							(end 0.2794 0.1778)
						)
						(arc
							(start 0.2794 -0.1778)
							(mid 0.249642 -0.249642)
							(end 0.1778 -0.2794)
						)
					)
					(width 0)
					(fill yes)
				)
			)
		)
		(pad "2" smd custom
			(at 0 0.4445 90)
			(size 0.1397 0.1397)
			(layers "F.Cu" "F.Mask" "F.Paste")
			(net "GND")
			(options
				(clearance outline)
				(anchor circle)
			)
			(primitives
				(gr_poly
					(pts
						(arc
							(start -0.1778 -0.2794)
							(mid -0.249642 -0.249642)
							(end -0.2794 -0.1778)
						)
						(arc
							(start -0.2794 0.1778)
							(mid -0.249642 0.249642)
							(end -0.1778 0.2794)
						)
						(arc
							(start 0.1778 0.2794)
							(mid 0.249642 0.249642)
							(end 0.2794 0.1778)
						)
						(arc
							(start 0.2794 -0.1778)
							(mid 0.249642 -0.249642)
							(end 0.1778 -0.2794)
						)
					)
					(width 0)
					(fill yes)
				)
			)
		)
	)
	(footprint ""
		(layer "F.Cu")
		(at 208.055972 -66.0908 90)
		(property "Reference" "C320"
			(at 0 0 90)
			(layer "F.SilkS")
			(hide yes)
			(effects
				(font
					(size 1.27 1.27)
				)
			)
		)
		(property "Value" "SCD01U16V1KX-GP"
			(at -2.8321 -1.7399 90)
			(unlocked yes)
			(layer "F.Fab")
			(hide yes)
			(effects
				(font
					(size 1.016 1.016)
					(thickness 0.1524)
				)
			)
		)
		(property "Device Type" "C0201H13"
			(at -2.8321 -3.2639 90)
			(unlocked yes)
			(layer "F.Fab")
			(hide yes)
			(effects
				(font
					(size 1.016 1.016)
					(thickness 0.1524)
				)
			)
		)
		(duplicate_pad_numbers_are_jumpers no)
		(fp_rect
			(start -0.2794 0.6477)
			(end 0.2794 -0.6477)
			(stroke
				(width 0)
				(type default)
			)
			(fill no)
			(layer "F.CrtYd")
		)
		(fp_rect
			(start -0.2794 0.6477)
			(end 0.2794 -0.6477)
			(stroke
				(width 0)
				(type default)
			)
			(fill no)
			(layer "F.Fab")
		)
		(pad "1" smd custom
			(at 0 -0.2794 90)
			(size 0.0762 0.0762)
			(layers "F.Cu" "F.Mask" "F.Paste")
			(net "PHY_IOC_TO_CON_B_2_DN_C")
			(options
				(clearance outline)
				(anchor circle)
			)
			(primitives
				(gr_poly
					(pts
						(arc
							(start 0.1524 -0.127)
							(mid 0.137521 -0.162921)
							(end 0.1016 -0.1778)
						)
						(arc
							(start -0.1016 -0.1778)
							(mid -0.137521 -0.162921)
							(end -0.1524 -0.127)
						)
						(arc
							(start -0.1524 0.127)
							(mid -0.137521 0.162921)
							(end -0.1016 0.1778)
						)
						(arc
							(start 0.1016 0.1778)
							(mid 0.137521 0.162921)
							(end 0.1524 0.127)
						)
					)
					(width 0)
					(fill yes)
				)
			)
		)
		(pad "2" smd custom
			(at 0 0.2794 90)
			(size 0.0762 0.0762)
			(layers "F.Cu" "F.Mask" "F.Paste")
			(net "PHY_IOC_TO_CON_B_2_DN")
			(options
				(clearance outline)
				(anchor circle)
			)
			(primitives
				(gr_poly
					(pts
						(arc
							(start 0.1524 -0.127)
							(mid 0.137521 -0.162921)
							(end 0.1016 -0.1778)
						)
						(arc
							(start -0.1016 -0.1778)
							(mid -0.137521 -0.162921)
							(end -0.1524 -0.127)
						)
						(arc
							(start -0.1524 0.127)
							(mid -0.137521 0.162921)
							(end -0.1016 0.1778)
						)
						(arc
							(start 0.1016 0.1778)
							(mid 0.137521 0.162921)
							(end 0.1524 0.127)
						)
					)
					(width 0)
					(fill yes)
				)
			)
		)
	)
	(footprint ""
		(layer "F.Cu")
		(at 88.9 -132.7658)
		(property "Reference" "R138"
			(at 0 0 0)
			(layer "F.SilkS")
			(hide yes)
			(effects
				(font
					(size 1.27 1.27)
				)
			)
		)
		(property "Value" "8K2R2J-3-GP"
			(at 0.064008 -3.993896 0)
			(unlocked yes)
			(layer "F.Fab")
			(hide yes)
			(effects
				(font
					(size 1.016 1.016)
					(thickness 0.1524)
				)
			)
		)
		(property "Device Type" "R402H16"
			(at 0.064008 -5.517896 0)
			(unlocked yes)
			(layer "F.Fab")
			(hide yes)
			(effects
				(font
					(size 1.016 1.016)
					(thickness 0.1524)
				)
			)
		)
		(duplicate_pad_numbers_are_jumpers no)
		(fp_line
			(start -0.508 -0.9398)
			(end -0.508 0.9398)
			(stroke
				(width 0.1524)
				(type default)
			)
			(layer "F.SilkS")
		)
		(fp_line
			(start 0.508 -0.9398)
			(end -0.508 -0.9398)
			(stroke
				(width 0.1524)
				(type default)
			)
			(layer "F.SilkS")
		)
		(fp_rect
			(start -0.508 0.9398)
			(end 0.508 -0.9398)
			(stroke
				(width 0)
				(type default)
			)
			(fill no)
			(layer "F.CrtYd")
		)
		(fp_rect
			(start -0.508 0.9398)
			(end 0.508 -0.9398)
			(stroke
				(width 0)
				(type default)
			)
			(fill no)
			(layer "F.Fab")
		)
		(pad "1" smd custom
			(at 0 -0.4445)
			(size 0.1397 0.1397)
			(layers "F.Cu" "F.Mask" "F.Paste")
			(net "EEPROM_A2")
			(options
				(clearance outline)
				(anchor circle)
			)
			(primitives
				(gr_poly
					(pts
						(arc
							(start -0.1778 -0.2794)
							(mid -0.249642 -0.249642)
							(end -0.2794 -0.1778)
						)
						(arc
							(start -0.2794 0.1778)
							(mid -0.249642 0.249642)
							(end -0.1778 0.2794)
						)
						(arc
							(start 0.1778 0.2794)
							(mid 0.249642 0.249642)
							(end 0.2794 0.1778)
						)
						(arc
							(start 0.2794 -0.1778)
							(mid 0.249642 -0.249642)
							(end 0.1778 -0.2794)
						)
					)
					(width 0)
					(fill yes)
				)
			)
		)
		(pad "2" smd custom
			(at 0 0.4445)
			(size 0.1397 0.1397)
			(layers "F.Cu" "F.Mask" "F.Paste")
			(net "GND")
			(options
				(clearance outline)
				(anchor circle)
			)
			(primitives
				(gr_poly
					(pts
						(arc
							(start -0.1778 -0.2794)
							(mid -0.249642 -0.249642)
							(end -0.2794 -0.1778)
						)
						(arc
							(start -0.2794 0.1778)
							(mid -0.249642 0.249642)
							(end -0.1778 0.2794)
						)
						(arc
							(start 0.1778 0.2794)
							(mid 0.249642 0.249642)
							(end 0.2794 0.1778)
						)
						(arc
							(start 0.2794 -0.1778)
							(mid 0.249642 -0.249642)
							(end 0.1778 -0.2794)
						)
					)
					(width 0)
					(fill yes)
				)
			)
		)
	)
	(footprint ""
		(layer "F.Cu")
		(at 172.5168 -117.094 180)
		(property "Reference" "C221"
			(at 0 0 180)
			(layer "F.SilkS")
			(hide yes)
			(effects
				(font
					(size 1.27 1.27)
				)
			)
		)
		(property "Value" "SCD1U25V2KX-2-GP"
			(at 1.1811 -2.7051 180)
			(unlocked yes)
			(layer "F.Fab")
			(hide yes)
			(effects
				(font
					(size 1.016 1.016)
					(thickness 0.1524)
				)
			)
		)
		(property "Device Type" "C402H22"
			(at 1.1811 -4.2291 180)
			(unlocked yes)
			(layer "F.Fab")
			(hide yes)
			(effects
				(font
					(size 1.016 1.016)
					(thickness 0.1524)
				)
			)
		)
		(duplicate_pad_numbers_are_jumpers no)
		(fp_rect
			(start -0.4318 0.9525)
			(end 0.4318 -0.9525)
			(stroke
				(width 0)
				(type default)
			)
			(fill no)
			(layer "F.CrtYd")
		)
		(fp_rect
			(start -0.4318 0.9525)
			(end 0.4318 -0.9525)
			(stroke
				(width 0)
				(type default)
			)
			(fill no)
			(layer "F.Fab")
		)
		(pad "1" smd custom
			(at 0 -0.4445 180)
			(size 0.1524 0.1524)
			(layers "F.Cu" "F.Mask" "F.Paste")
			(net "P1V8")
			(options
				(clearance outline)
				(anchor circle)
			)
			(primitives
				(gr_poly
					(pts
						(arc
							(start 0.3048 -0.2032)
							(mid 0.275042 -0.275042)
							(end 0.2032 -0.3048)
						)
						(arc
							(start -0.2032 -0.3048)
							(mid -0.275042 -0.275042)
							(end -0.3048 -0.2032)
						)
						(arc
							(start -0.3048 0.2032)
							(mid -0.275042 0.275042)
							(end -0.2032 0.3048)
						)
						(arc
							(start 0.2032 0.3048)
							(mid 0.275042 0.275042)
							(end 0.3048 0.2032)
						)
					)
					(width 0)
					(fill yes)
				)
			)
		)
		(pad "2" smd custom
			(at 0 0.4445 180)
			(size 0.1524 0.1524)
			(layers "F.Cu" "F.Mask" "F.Paste")
			(net "GND")
			(options
				(clearance outline)
				(anchor circle)
			)
			(primitives
				(gr_poly
					(pts
						(arc
							(start 0.3048 -0.2032)
							(mid 0.275042 -0.275042)
							(end 0.2032 -0.3048)
						)
						(arc
							(start -0.2032 -0.3048)
							(mid -0.275042 -0.275042)
							(end -0.3048 -0.2032)
						)
						(arc
							(start -0.3048 0.2032)
							(mid -0.275042 0.275042)
							(end -0.2032 0.3048)
						)
						(arc
							(start 0.2032 0.3048)
							(mid 0.275042 0.275042)
							(end 0.3048 0.2032)
						)
					)
					(width 0)
					(fill yes)
				)
			)
		)
	)
)
